# S9S_MB_2U (Grand Teton) — schematic netlist excerpt (pin names and nets, part order shuffled) for the footprints in the layout excerpt that follows; sources: Cadence DE-HDL packaged netlist, KiCad conversion of 03242023_DA0F0TMBIJ0_F0T_Motherboard_J_brd_V01_OCP.brd

C1316  Q_CAP  0.047UF 25V 10% X7R  pkg C0402  page 244 : A = FM_COMP_P3V3_STBY_CEXT ; B = GND
PC2229  Q_CAP  0.22UF 16V 10% X7R  pkg 0402  page 242 : A = P12V_SCM_TIMER ; B = GND
C901  Q_CAP_DIFFBUS  DIFF BUS_0.22UF 6.3V 20% X6S  pkg C0201  page 174 : \1\ = P5E_CPU0_PE3_TX_C_DP<0> ; \2\ = P5E_CPU0_PE3_TX_DP<0>

(kicad_pcb
	(version 20260206)
	(generator "pcbnew")
	(generator_version "10.0")
	(general
		(thickness 1.6)
		(legacy_teardrops no)
	)
	(paper "A4")
	(title_block
		(title "03242023_DA0F0TMBIJ0_F0T_Motherboard_J_brd_V01_OCP.brd")
		(comment 1 "Grand Teton / footprints 167-169 of 6105")
	)
	(layers
		(0 "F.Cu" signal "TOP")
		(4 "In1.Cu" signal "GND")
		(6 "In2.Cu" signal "IN1")
		(8 "In3.Cu" signal "GND1")
		(10 "In4.Cu" signal "IN2")
		(12 "In5.Cu" signal "GND2")
		(14 "In6.Cu" signal "IN3")
		(16 "In7.Cu" signal "GND3")
		(18 "In8.Cu" signal "VCC")
		(20 "In9.Cu" signal "VCC1")
		(22 "In10.Cu" signal "GND4")
		(24 "In11.Cu" signal "IN4")
		(26 "In12.Cu" signal "GND5")
		(28 "In13.Cu" signal "IN5")
		(30 "In14.Cu" signal "GND6")
		(32 "In15.Cu" signal "IN6")
		(34 "In16.Cu" signal "GND7")
		(2 "B.Cu" signal "BOTTOM")
		(9 "F.Adhes" user "F.Adhesive")
		(11 "B.Adhes" user "B.Adhesive")
		(13 "F.Paste" user "Package Geometry/Pastemask Top")
		(15 "B.Paste" user "Package Geometry/Pastemask Bottom")
		(5 "F.SilkS" user "Ref Des/Silkscreen Top")
		(7 "B.SilkS" user "Ref Des/Silkscreen Bottom")
		(1 "F.Mask" user "Board Geometry/Soldermask Top")
		(3 "B.Mask" user "Board Geometry/Soldermask Bottom")
		(17 "Dwgs.User" user "User.Drawings")
		(19 "Cmts.User" user "User.Comments")
		(21 "Eco1.User" user "User.Eco1")
		(23 "Eco2.User" user "User.Eco2")
		(25 "Edge.Cuts" user "Board Geometry/Outline")
		(27 "Margin" user)
		(31 "F.CrtYd" user "Package Geometry/Place Bound Top")
		(29 "B.CrtYd" user "Package Geometry/Place Bound Bottom")
		(35 "F.Fab" user "Ref Des/Assembly Top")
		(33 "B.Fab" user "Ref Des/Assembly Bottom")
	)
	(footprint ""
		(layer "F.Cu")
		(at 179.058062 -32.935672 90)
		(property "Reference" "PC2229"
			(at 0 0 90)
			(layer "F.SilkS")
			(hide yes)
			(effects
				(font
					(size 1.27 1.27)
				)
			)
		)
		(property "Value" ""
			(at 0 0 90)
			(layer "F.Fab")
			(effects
				(font
					(size 1.27 1.27)
				)
			)
		)
		(duplicate_pad_numbers_are_jumpers no)
		(fp_line
			(start 0.7874 -0.4064)
			(end 0.7874 0.4064)
			(stroke
				(width 0.1524)
				(type default)
			)
			(layer "F.SilkS")
		)
		(fp_line
			(start -0.7874 -0.4064)
			(end 0.7874 -0.4064)
			(stroke
				(width 0.1524)
				(type default)
			)
			(layer "F.SilkS")
		)
		(fp_line
			(start 0.7874 0.4064)
			(end -0.7874 0.4064)
			(stroke
				(width 0.1524)
				(type default)
			)
			(layer "F.SilkS")
		)
		(fp_line
			(start -0.7874 0.4064)
			(end -0.7874 -0.4064)
			(stroke
				(width 0.1524)
				(type default)
			)
			(layer "F.SilkS")
		)
		(fp_line
			(start -0.12065 -0.305054)
			(end -0.12065 -0.2794)
			(stroke
				(width 0.1)
				(type default)
			)
			(layer "F.Fab")
		)
		(fp_line
			(start -0.67945 -0.305054)
			(end -0.12065 -0.305054)
			(stroke
				(width 0.1)
				(type default)
			)
			(layer "F.Fab")
		)
		(fp_line
			(start 0.67945 -0.3048)
			(end 0.67945 0.3048)
			(stroke
				(width 0.1)
				(type default)
			)
			(layer "F.Fab")
		)
		(fp_line
			(start 0.12065 -0.3048)
			(end 0.67945 -0.3048)
			(stroke
				(width 0.1)
				(type default)
			)
			(layer "F.Fab")
		)
		(fp_line
			(start 0.12065 -0.2794)
			(end 0.12065 -0.3048)
			(stroke
				(width 0.1)
				(type default)
			)
			(layer "F.Fab")
		)
		(fp_line
			(start -0.12065 -0.2794)
			(end 0.12065 -0.2794)
			(stroke
				(width 0.1)
				(type default)
			)
			(layer "F.Fab")
		)
		(fp_line
			(start 0.120396 0.2794)
			(end -0.12065 0.2794)
			(stroke
				(width 0.1)
				(type default)
			)
			(layer "F.Fab")
		)
		(fp_line
			(start -0.12065 0.2794)
			(end -0.12065 0.3048)
			(stroke
				(width 0.1)
				(type default)
			)
			(layer "F.Fab")
		)
		(fp_line
			(start 0.67945 0.3048)
			(end 0.120396 0.3048)
			(stroke
				(width 0.1)
				(type default)
			)
			(layer "F.Fab")
		)
		(fp_line
			(start 0.120396 0.3048)
			(end 0.120396 0.2794)
			(stroke
				(width 0.1)
				(type default)
			)
			(layer "F.Fab")
		)
		(fp_line
			(start -0.12065 0.3048)
			(end -0.67945 0.3048)
			(stroke
				(width 0.1)
				(type default)
			)
			(layer "F.Fab")
		)
		(fp_line
			(start -0.67945 0.3048)
			(end -0.67945 -0.305054)
			(stroke
				(width 0.1)
				(type default)
			)
			(layer "F.Fab")
		)
		(pad "1" smd circle
			(at -0.40005 0 90)
			(size 0 0)
			(layers "F.Cu" "F.Mask" "F.Paste")
			(net "P12V_SCM_TIMER")
		)
		(pad "2" smd circle
			(at 0.40005 0 90)
			(size 0 0)
			(layers "F.Cu" "F.Mask" "F.Paste")
			(net "GND")
		)
	)
	(footprint ""
		(layer "F.Cu")
		(at 418.69233 -408.517344 -90)
		(property "Reference" "C901"
			(at 0 0 270)
			(layer "F.SilkS")
			(hide yes)
			(effects
				(font
					(size 1.27 1.27)
				)
			)
		)
		(property "Value" ""
			(at 0 0 270)
			(layer "F.Fab")
			(effects
				(font
					(size 1.27 1.27)
				)
			)
		)
		(duplicate_pad_numbers_are_jumpers no)
		(fp_line
			(start -0.299974 0.150114)
			(end -0.299974 -0.150114)
			(stroke
				(width 0.1)
				(type default)
			)
			(layer "F.Fab")
		)
		(fp_line
			(start 0.299974 0.150114)
			(end -0.299974 0.150114)
			(stroke
				(width 0.1)
				(type default)
			)
			(layer "F.Fab")
		)
		(fp_line
			(start -0.299974 -0.150114)
			(end 0.299974 -0.150114)
			(stroke
				(width 0.1)
				(type default)
			)
			(layer "F.Fab")
		)
		(fp_line
			(start 0.299974 -0.150114)
			(end 0.299974 0.150114)
			(stroke
				(width 0.1)
				(type default)
			)
			(layer "F.Fab")
		)
		(pad "1" smd rect
			(at -0.2667 0 270)
			(size 0.3048 0.381)
			(layers "F.Cu" "F.Mask" "F.Paste")
			(net "P5E_CPU0_PE3_TX_C_DP<0>")
		)
		(pad "2" smd rect
			(at 0.2667 0 270)
			(size 0.3048 0.381)
			(layers "F.Cu" "F.Mask" "F.Paste")
			(net "P5E_CPU0_PE3_TX_DP<0>")
		)
	)
	(footprint ""
		(layer "F.Cu")
		(at 218.12758 -130.957828)
		(property "Reference" "C1316"
			(at 0 0 0)
			(layer "F.SilkS")
			(hide yes)
			(effects
				(font
					(size 1.27 1.27)
				)
			)
		)
		(property "Value" ""
			(at 0 0 0)
			(layer "F.Fab")
			(effects
				(font
					(size 1.27 1.27)
				)
			)
		)
		(duplicate_pad_numbers_are_jumpers no)
		(fp_line
			(start -0.7874 -0.4064)
			(end 0.7874 -0.4064)
			(stroke
				(width 0.1524)
				(type default)
			)
			(layer "F.SilkS")
		)
		(fp_line
			(start -0.7874 0.4064)
			(end -0.7874 -0.4064)
			(stroke
				(width 0.1524)
				(type default)
			)
			(layer "F.SilkS")
		)
		(fp_line
			(start 0.7874 -0.4064)
			(end 0.7874 0.4064)
			(stroke
				(width 0.1524)
				(type default)
			)
			(layer "F.SilkS")
		)
		(fp_line
			(start 0.7874 0.4064)
			(end -0.7874 0.4064)
			(stroke
				(width 0.1524)
				(type default)
			)
			(layer "F.SilkS")
		)
		(fp_line
			(start -0.67945 -0.305054)
			(end -0.12065 -0.305054)
			(stroke
				(width 0.1)
				(type default)
			)
			(layer "F.Fab")
		)
		(fp_line
			(start -0.67945 0.3048)
			(end -0.67945 -0.305054)
			(stroke
				(width 0.1)
				(type default)
			)
			(layer "F.Fab")
		)
		(fp_line
			(start -0.12065 -0.305054)
			(end -0.12065 -0.2794)
			(stroke
				(width 0.1)
				(type default)
			)
			(layer "F.Fab")
		)
		(fp_line
			(start -0.12065 -0.2794)
			(end 0.12065 -0.2794)
			(stroke
				(width 0.1)
				(type default)
			)
			(layer "F.Fab")
		)
		(fp_line
			(start -0.12065 0.2794)
			(end -0.12065 0.3048)
			(stroke
				(width 0.1)
				(type default)
			)
			(layer "F.Fab")
		)
		(fp_line
			(start -0.12065 0.3048)
			(end -0.67945 0.3048)
			(stroke
				(width 0.1)
				(type default)
			)
			(layer "F.Fab")
		)
		(fp_line
			(start 0.120396 0.2794)
			(end -0.12065 0.2794)
			(stroke
				(width 0.1)
				(type default)
			)
			(layer "F.Fab")
		)
		(fp_line
			(start 0.120396 0.3048)
			(end 0.120396 0.2794)
			(stroke
				(width 0.1)
				(type default)
			)
			(layer "F.Fab")
		)
		(fp_line
			(start 0.12065 -0.3048)
			(end 0.67945 -0.3048)
			(stroke
				(width 0.1)
				(type default)
			)
			(layer "F.Fab")
		)
		(fp_line
			(start 0.12065 -0.2794)
			(end 0.12065 -0.3048)
			(stroke
				(width 0.1)
				(type default)
			)
			(layer "F.Fab")
		)
		(fp_line
			(start 0.67945 -0.3048)
			(end 0.67945 0.3048)
			(stroke
				(width 0.1)
				(type default)
			)
			(layer "F.Fab")
		)
		(fp_line
			(start 0.67945 0.3048)
			(end 0.120396 0.3048)
			(stroke
				(width 0.1)
				(type default)
			)
			(layer "F.Fab")
		)
		(pad "1" smd circle
			(at -0.40005 0)
			(size 0 0)
			(layers "F.Cu" "F.Mask" "F.Paste")
			(net "FM_COMP_P3V3_STBY_CEXT")
		)
		(pad "2" smd circle
			(at 0.40005 0)
			(size 0 0)
			(layers "F.Cu" "F.Mask" "F.Paste")
			(net "GND")
		)
	)
)
